(kicad_pcb
	(version 20260206)
	(generator "pcbnew")
	(generator_version "10.0")
	(general
		(thickness 1.6)
		(legacy_teardrops no)
	)
	(paper "A4")
	(title_block
		(title "01162023_DA0F0TEBIF0_F0T_Expander_BD_F_brd_V02_OCP.brd")
		(comment 1 "Grand Teton / footprints 2164-2170 of 9728")
	)
	(layers
		(0 "F.Cu" signal "TOP")
		(4 "In1.Cu" signal "GND")
		(6 "In2.Cu" signal "VCC")
		(8 "In3.Cu" signal "VCC1")
		(10 "In4.Cu" signal "GND1")
		(12 "In5.Cu" signal "IN1")
		(14 "In6.Cu" signal "GND2")
		(16 "In7.Cu" signal "IN2")
		(18 "In8.Cu" signal "GND3")
		(20 "In9.Cu" signal "IN3")
		(22 "In10.Cu" signal "GND4")
		(24 "In11.Cu" signal "IN4")
		(26 "In12.Cu" signal "GND5")
		(28 "In13.Cu" signal "IN5")
		(30 "In14.Cu" signal "GND6")
		(32 "In15.Cu" signal "IN6")
		(34 "In16.Cu" signal "GND7")
		(2 "B.Cu" signal "BOTTOM")
		(9 "F.Adhes" user "F.Adhesive")
		(11 "B.Adhes" user "B.Adhesive")
		(13 "F.Paste" user "Package Geometry/Pastemask Top")
		(15 "B.Paste" user "Package Geometry/Pastemask Bottom")
		(5 "F.SilkS" user "Ref Des/Silkscreen Top")
		(7 "B.SilkS" user "Ref Des/Silkscreen Bottom")
		(1 "F.Mask" user "Board Geometry/Soldermask Top")
		(3 "B.Mask" user "Board Geometry/Soldermask Bottom")
		(17 "Dwgs.User" user "User.Drawings")
		(19 "Cmts.User" user "User.Comments")
		(21 "Eco1.User" user "User.Eco1")
		(23 "Eco2.User" user "User.Eco2")
		(25 "Edge.Cuts" user "Board Geometry/Outline")
		(27 "Margin" user)
		(31 "F.CrtYd" user "Package Geometry/Place Bound Top")
		(29 "B.CrtYd" user "Package Geometry/Place Bound Bottom")
		(35 "F.Fab" user "Ref Des/Assembly Top")
		(33 "B.Fab" user "Ref Des/Assembly Bottom")
	)
	(footprint ""
		(layer "F.Cu")
		(at 210.439 -208.407)
		(property "Reference" "C2706"
			(at 0 0 0)
			(layer "F.SilkS")
			(hide yes)
			(effects
				(font
					(size 1.27 1.27)
				)
			)
		)
		(property "Value" ""
			(at 0 0 0)
			(layer "F.Fab")
			(effects
				(font
					(size 1.27 1.27)
				)
			)
		)
		(duplicate_pad_numbers_are_jumpers no)
		(fp_line
			(start -0.7874 -0.4064)
			(end 0.7874 -0.4064)
			(stroke
				(width 0.1524)
				(type default)
			)
			(layer "F.SilkS")
		)
		(fp_line
			(start -0.7874 0.4064)
			(end -0.7874 -0.4064)
			(stroke
				(width 0.1524)
				(type default)
			)
			(layer "F.SilkS")
		)
		(fp_line
			(start 0.7874 -0.4064)
			(end 0.7874 0.4064)
			(stroke
				(width 0.1524)
				(type default)
			)
			(layer "F.SilkS")
		)
		(fp_line
			(start 0.7874 0.4064)
			(end -0.7874 0.4064)
			(stroke
				(width 0.1524)
				(type default)
			)
			(layer "F.SilkS")
		)
		(fp_line
			(start -0.67945 -0.305054)
			(end -0.12065 -0.305054)
			(stroke
				(width 0.1)
				(type default)
			)
			(layer "F.Fab")
		)
		(fp_line
			(start -0.67945 0.3048)
			(end -0.67945 -0.305054)
			(stroke
				(width 0.1)
				(type default)
			)
			(layer "F.Fab")
		)
		(fp_line
			(start -0.12065 -0.305054)
			(end -0.12065 -0.2794)
			(stroke
				(width 0.1)
				(type default)
			)
			(layer "F.Fab")
		)
		(fp_line
			(start -0.12065 -0.2794)
			(end 0.12065 -0.2794)
			(stroke
				(width 0.1)
				(type default)
			)
			(layer "F.Fab")
		)
		(fp_line
			(start -0.12065 0.2794)
			(end -0.12065 0.3048)
			(stroke
				(width 0.1)
				(type default)
			)
			(layer "F.Fab")
		)
		(fp_line
			(start -0.12065 0.3048)
			(end -0.67945 0.3048)
			(stroke
				(width 0.1)
				(type default)
			)
			(layer "F.Fab")
		)
		(fp_line
			(start 0.120396 0.2794)
			(end -0.12065 0.2794)
			(stroke
				(width 0.1)
				(type default)
			)
			(layer "F.Fab")
		)
		(fp_line
			(start 0.120396 0.3048)
			(end 0.120396 0.2794)
			(stroke
				(width 0.1)
				(type default)
			)
			(layer "F.Fab")
		)
		(fp_line
			(start 0.12065 -0.3048)
			(end 0.67945 -0.3048)
			(stroke
				(width 0.1)
				(type default)
			)
			(layer "F.Fab")
		)
		(fp_line
			(start 0.12065 -0.2794)
			(end 0.12065 -0.3048)
			(stroke
				(width 0.1)
				(type default)
			)
			(layer "F.Fab")
		)
		(fp_line
			(start 0.67945 -0.3048)
			(end 0.67945 0.3048)
			(stroke
				(width 0.1)
				(type default)
			)
			(layer "F.Fab")
		)
		(fp_line
			(start 0.67945 0.3048)
			(end 0.120396 0.3048)
			(stroke
				(width 0.1)
				(type default)
			)
			(layer "F.Fab")
		)
		(pad "1" smd circle
			(at -0.40005 0)
			(size 0 0)
			(layers "F.Cu" "F.Mask" "F.Paste")
			(net "GND")
		)
		(pad "2" smd circle
			(at 0.40005 0)
			(size 0 0)
			(layers "F.Cu" "F.Mask" "F.Paste")
			(net "P1V2_AUX")
		)
	)
	(footprint ""
		(layer "F.Cu")
		(at 208.489804 -298.885102 -90)
		(property "Reference" "R3928"
			(at 0 0 270)
			(layer "F.SilkS")
			(hide yes)
			(effects
				(font
					(size 1.27 1.27)
				)
			)
		)
		(property "Value" ""
			(at 0 0 270)
			(layer "F.Fab")
			(effects
				(font
					(size 1.27 1.27)
				)
			)
		)
		(duplicate_pad_numbers_are_jumpers no)
		(fp_line
			(start -0.7874 0.4064)
			(end -0.7874 -0.4064)
			(stroke
				(width 0.1524)
				(type default)
			)
			(layer "F.SilkS")
		)
		(fp_line
			(start 0.7874 0.4064)
			(end -0.7874 0.4064)
			(stroke
				(width 0.1524)
				(type default)
			)
			(layer "F.SilkS")
		)
		(fp_line
			(start -0.7874 -0.4064)
			(end 0.7874 -0.4064)
			(stroke
				(width 0.1524)
				(type default)
			)
			(layer "F.SilkS")
		)
		(fp_line
			(start 0.7874 -0.4064)
			(end 0.7874 0.4064)
			(stroke
				(width 0.1524)
				(type default)
			)
			(layer "F.SilkS")
		)
		(fp_line
			(start -0.67945 0.3048)
			(end -0.67945 -0.305054)
			(stroke
				(width 0.1)
				(type default)
			)
			(layer "F.Fab")
		)
		(fp_line
			(start -0.12065 0.3048)
			(end -0.67945 0.3048)
			(stroke
				(width 0.1)
				(type default)
			)
			(layer "F.Fab")
		)
		(fp_line
			(start 0.120396 0.3048)
			(end 0.120396 0.2794)
			(stroke
				(width 0.1)
				(type default)
			)
			(layer "F.Fab")
		)
		(fp_line
			(start 0.67945 0.3048)
			(end 0.120396 0.3048)
			(stroke
				(width 0.1)
				(type default)
			)
			(layer "F.Fab")
		)
		(fp_line
			(start -0.12065 0.2794)
			(end -0.12065 0.3048)
			(stroke
				(width 0.1)
				(type default)
			)
			(layer "F.Fab")
		)
		(fp_line
			(start 0.120396 0.2794)
			(end -0.12065 0.2794)
			(stroke
				(width 0.1)
				(type default)
			)
			(layer "F.Fab")
		)
		(fp_line
			(start -0.12065 -0.2794)
			(end 0.12065 -0.2794)
			(stroke
				(width 0.1)
				(type default)
			)
			(layer "F.Fab")
		)
		(fp_line
			(start 0.12065 -0.2794)
			(end 0.12065 -0.3048)
			(stroke
				(width 0.1)
				(type default)
			)
			(layer "F.Fab")
		)
		(fp_line
			(start 0.12065 -0.3048)
			(end 0.67945 -0.3048)
			(stroke
				(width 0.1)
				(type default)
			)
			(layer "F.Fab")
		)
		(fp_line
			(start 0.67945 -0.3048)
			(end 0.67945 0.3048)
			(stroke
				(width 0.1)
				(type default)
			)
			(layer "F.Fab")
		)
		(fp_line
			(start -0.67945 -0.305054)
			(end -0.12065 -0.305054)
			(stroke
				(width 0.1)
				(type default)
			)
			(layer "F.Fab")
		)
		(fp_line
			(start -0.12065 -0.305054)
			(end -0.12065 -0.2794)
			(stroke
				(width 0.1)
				(type default)
			)
			(layer "F.Fab")
		)
		(pad "1" smd circle
			(at -0.40005 0 270)
			(size 0 0)
			(layers "F.Cu" "F.Mask" "F.Paste")
			(net "I2C_PEX1_HOST_SCL")
		)
		(pad "2" smd circle
			(at 0.40005 0 270)
			(size 0 0)
			(layers "F.Cu" "F.Mask" "F.Paste")
			(net "I2C_PEX1_HOST_R_SCL")
		)
	)
	(footprint ""
		(layer "F.Cu")
		(at 253.147322 -20.35556)
		(property "Reference" "C3932"
			(at 0 0 0)
			(layer "F.SilkS")
			(hide yes)
			(effects
				(font
					(size 1.27 1.27)
				)
			)
		)
		(property "Value" ""
			(at 0 0 0)
			(layer "F.Fab")
			(effects
				(font
					(size 1.27 1.27)
				)
			)
		)
		(duplicate_pad_numbers_are_jumpers no)
		(fp_line
			(start -0.7874 -0.4064)
			(end 0.7874 -0.4064)
			(stroke
				(width 0.1524)
				(type default)
			)
			(layer "F.SilkS")
		)
		(fp_line
			(start -0.7874 0.4064)
			(end -0.7874 -0.4064)
			(stroke
				(width 0.1524)
				(type default)
			)
			(layer "F.SilkS")
		)
		(fp_line
			(start 0.7874 -0.4064)
			(end 0.7874 0.4064)
			(stroke
				(width 0.1524)
				(type default)
			)
			(layer "F.SilkS")
		)
		(fp_line
			(start 0.7874 0.4064)
			(end -0.7874 0.4064)
			(stroke
				(width 0.1524)
				(type default)
			)
			(layer "F.SilkS")
		)
		(fp_line
			(start -0.67945 -0.305054)
			(end -0.12065 -0.305054)
			(stroke
				(width 0.1)
				(type default)
			)
			(layer "F.Fab")
		)
		(fp_line
			(start -0.67945 0.3048)
			(end -0.67945 -0.305054)
			(stroke
				(width 0.1)
				(type default)
			)
			(layer "F.Fab")
		)
		(fp_line
			(start -0.12065 -0.305054)
			(end -0.12065 -0.2794)
			(stroke
				(width 0.1)
				(type default)
			)
			(layer "F.Fab")
		)
		(fp_line
			(start -0.12065 -0.2794)
			(end 0.12065 -0.2794)
			(stroke
				(width 0.1)
				(type default)
			)
			(layer "F.Fab")
		)
		(fp_line
			(start -0.12065 0.2794)
			(end -0.12065 0.3048)
			(stroke
				(width 0.1)
				(type default)
			)
			(layer "F.Fab")
		)
		(fp_line
			(start -0.12065 0.3048)
			(end -0.67945 0.3048)
			(stroke
				(width 0.1)
				(type default)
			)
			(layer "F.Fab")
		)
		(fp_line
			(start 0.120396 0.2794)
			(end -0.12065 0.2794)
			(stroke
				(width 0.1)
				(type default)
			)
			(layer "F.Fab")
		)
		(fp_line
			(start 0.120396 0.3048)
			(end 0.120396 0.2794)
			(stroke
				(width 0.1)
				(type default)
			)
			(layer "F.Fab")
		)
		(fp_line
			(start 0.12065 -0.3048)
			(end 0.67945 -0.3048)
			(stroke
				(width 0.1)
				(type default)
			)
			(layer "F.Fab")
		)
		(fp_line
			(start 0.12065 -0.2794)
			(end 0.12065 -0.3048)
			(stroke
				(width 0.1)
				(type default)
			)
			(layer "F.Fab")
		)
		(fp_line
			(start 0.67945 -0.3048)
			(end 0.67945 0.3048)
			(stroke
				(width 0.1)
				(type default)
			)
			(layer "F.Fab")
		)
		(fp_line
			(start 0.67945 0.3048)
			(end 0.120396 0.3048)
			(stroke
				(width 0.1)
				(type default)
			)
			(layer "F.Fab")
		)
		(pad "1" smd circle
			(at -0.40005 0)
			(size 0 0)
			(layers "F.Cu" "F.Mask" "F.Paste")
			(net "P12V_SSD8")
		)
		(pad "2" smd circle
			(at 0.40005 0)
			(size 0 0)
			(layers "F.Cu" "F.Mask" "F.Paste")
			(net "GND")
		)
	)
	(footprint ""
		(layer "F.Cu")
		(at 366.243362 -114.152426 -90)
		(property "Reference" "PC911"
			(at 0 0 270)
			(layer "F.SilkS")
			(hide yes)
			(effects
				(font
					(size 1.27 1.27)
				)
			)
		)
		(property "Value" ""
			(at 0 0 270)
			(layer "F.Fab")
			(effects
				(font
					(size 1.27 1.27)
				)
			)
		)
		(duplicate_pad_numbers_are_jumpers no)
		(fp_line
			(start -1.524 0.762)
			(end -1.524 -0.762)
			(stroke
				(width 0.1524)
				(type default)
			)
			(layer "F.SilkS")
		)
		(fp_line
			(start 1.524 0.762)
			(end -1.524 0.762)
			(stroke
				(width 0.1524)
				(type default)
			)
			(layer "F.SilkS")
		)
		(fp_line
			(start -1.524 -0.762)
			(end 1.524 -0.762)
			(stroke
				(width 0.1524)
				(type default)
			)
			(layer "F.SilkS")
		)
		(fp_line
			(start 1.524 -0.762)
			(end 1.524 0.762)
			(stroke
				(width 0.1524)
				(type default)
			)
			(layer "F.SilkS")
		)
		(fp_line
			(start -1.1049 0.724916)
			(end 1.1049 0.724916)
			(stroke
				(width 0.1)
				(type default)
			)
			(layer "F.Fab")
		)
		(fp_line
			(start 1.1049 0.724916)
			(end 1.1049 -0.724916)
			(stroke
				(width 0.1)
				(type default)
			)
			(layer "F.Fab")
		)
		(fp_line
			(start -1.1049 -0.724916)
			(end -1.1049 0.724916)
			(stroke
				(width 0.1)
				(type default)
			)
			(layer "F.Fab")
		)
		(fp_line
			(start 1.1049 -0.724916)
			(end -1.1049 -0.724916)
			(stroke
				(width 0.1)
				(type default)
			)
			(layer "F.Fab")
		)
		(pad "1" smd rect
			(at -0.889 0 90)
			(size 1.016 1.27)
			(layers "F.Cu" "F.Mask" "F.Paste")
			(net "P3V3_NIC6")
		)
		(pad "2" smd rect
			(at 0.889 0 90)
			(size 1.016 1.27)
			(layers "F.Cu" "F.Mask" "F.Paste")
			(net "GND")
		)
	)
	(footprint ""
		(layer "F.Cu")
		(at 236.927136 -266.873228 180)
		(property "Reference" "L116"
			(at 0 0 180)
			(layer "F.SilkS")
			(hide yes)
			(effects
				(font
					(size 1.27 1.27)
				)
			)
		)
		(property "Value" ""
			(at 0 0 180)
			(layer "F.Fab")
			(effects
				(font
					(size 1.27 1.27)
				)
			)
		)
		(duplicate_pad_numbers_are_jumpers no)
		(fp_line
			(start 2.248154 4.9911)
			(end 2.248154 1.672336)
			(stroke
				(width 0.1524)
				(type default)
			)
			(layer "F.SilkS")
		)
		(fp_line
			(start 2.248154 -1.687576)
			(end 2.248154 -4.9911)
			(stroke
				(width 0.1524)
				(type default)
			)
			(layer "F.SilkS")
		)
		(fp_line
			(start 2.248154 -4.9911)
			(end -2.248154 -4.9911)
			(stroke
				(width 0.1524)
				(type default)
			)
			(layer "F.SilkS")
		)
		(fp_line
			(start -2.248154 4.9911)
			(end 2.248154 4.9911)
			(stroke
				(width 0.1524)
				(type default)
			)
			(layer "F.SilkS")
		)
		(fp_line
			(start -2.248154 1.76022)
			(end -2.248154 4.9911)
			(stroke
				(width 0.1524)
				(type default)
			)
			(layer "F.SilkS")
		)
		(fp_line
			(start -2.248154 -4.9911)
			(end -2.248154 -1.665478)
			(stroke
				(width 0.1524)
				(type default)
			)
			(layer "F.SilkS")
		)
		(fp_line
			(start 1.700022 0.899922)
			(end 1.700022 -0.899922)
			(stroke
				(width 0.1)
				(type default)
			)
			(layer "F.Fab")
		)
		(fp_line
			(start 1.700022 -0.899922)
			(end -1.700022 -0.899922)
			(stroke
				(width 0.1)
				(type default)
			)
			(layer "F.Fab")
		)
		(fp_line
			(start -1.700022 0.899922)
			(end 1.700022 0.899922)
			(stroke
				(width 0.1)
				(type default)
			)
			(layer "F.Fab")
		)
		(fp_line
			(start -1.700022 -0.899922)
			(end -1.700022 0.899922)
			(stroke
				(width 0.1)
				(type default)
			)
			(layer "F.Fab")
		)
		(pad "1" smd rect
			(at -1.575054 0 180)
			(size 1.1684 9.8044)
			(layers "F.Cu" "F.Mask" "F.Paste")
			(net "P1V25_PEX2")
		)
		(pad "2" smd rect
			(at 1.575054 0 180)
			(size 1.1684 9.8044)
			(layers "F.Cu" "F.Mask" "F.Paste")
			(net "P1V25_SERDES_VDDPLL_PEX2")
		)
	)
	(footprint ""
		(layer "F.Cu")
		(at 336.042 -151.003)
		(property "Reference" "R4805"
			(at 0 0 0)
			(layer "F.SilkS")
			(hide yes)
			(effects
				(font
					(size 1.27 1.27)
				)
			)
		)
		(property "Value" ""
			(at 0 0 0)
			(layer "F.Fab")
			(effects
				(font
					(size 1.27 1.27)
				)
			)
		)
		(duplicate_pad_numbers_are_jumpers no)
		(fp_line
			(start -0.7874 -0.4064)
			(end 0.7874 -0.4064)
			(stroke
				(width 0.1524)
				(type default)
			)
			(layer "F.SilkS")
		)
		(fp_line
			(start -0.7874 0.4064)
			(end -0.7874 -0.4064)
			(stroke
				(width 0.1524)
				(type default)
			)
			(layer "F.SilkS")
		)
		(fp_line
			(start 0.7874 -0.4064)
			(end 0.7874 0.4064)
			(stroke
				(width 0.1524)
				(type default)
			)
			(layer "F.SilkS")
		)
		(fp_line
			(start 0.7874 0.4064)
			(end -0.7874 0.4064)
			(stroke
				(width 0.1524)
				(type default)
			)
			(layer "F.SilkS")
		)
		(fp_line
			(start -0.67945 -0.305054)
			(end -0.12065 -0.305054)
			(stroke
				(width 0.1)
				(type default)
			)
			(layer "F.Fab")
		)
		(fp_line
			(start -0.67945 0.3048)
			(end -0.67945 -0.305054)
			(stroke
				(width 0.1)
				(type default)
			)
			(layer "F.Fab")
		)
		(fp_line
			(start -0.12065 -0.305054)
			(end -0.12065 -0.2794)
			(stroke
				(width 0.1)
				(type default)
			)
			(layer "F.Fab")
		)
		(fp_line
			(start -0.12065 -0.2794)
			(end 0.12065 -0.2794)
			(stroke
				(width 0.1)
				(type default)
			)
			(layer "F.Fab")
		)
		(fp_line
			(start -0.12065 0.2794)
			(end -0.12065 0.3048)
			(stroke
				(width 0.1)
				(type default)
			)
			(layer "F.Fab")
		)
		(fp_line
			(start -0.12065 0.3048)
			(end -0.67945 0.3048)
			(stroke
				(width 0.1)
				(type default)
			)
			(layer "F.Fab")
		)
		(fp_line
			(start 0.120396 0.2794)
			(end -0.12065 0.2794)
			(stroke
				(width 0.1)
				(type default)
			)
			(layer "F.Fab")
		)
		(fp_line
			(start 0.120396 0.3048)
			(end 0.120396 0.2794)
			(stroke
				(width 0.1)
				(type default)
			)
			(layer "F.Fab")
		)
		(fp_line
			(start 0.12065 -0.3048)
			(end 0.67945 -0.3048)
			(stroke
				(width 0.1)
				(type default)
			)
			(layer "F.Fab")
		)
		(fp_line
			(start 0.12065 -0.2794)
			(end 0.12065 -0.3048)
			(stroke
				(width 0.1)
				(type default)
			)
			(layer "F.Fab")
		)
		(fp_line
			(start 0.67945 -0.3048)
			(end 0.67945 0.3048)
			(stroke
				(width 0.1)
				(type default)
			)
			(layer "F.Fab")
		)
		(fp_line
			(start 0.67945 0.3048)
			(end 0.120396 0.3048)
			(stroke
				(width 0.1)
				(type default)
			)
			(layer "F.Fab")
		)
		(pad "1" smd circle
			(at -0.40005 0)
			(size 0 0)
			(layers "F.Cu" "F.Mask" "F.Paste")
			(net "PEX3_PCA9555_INT_N")
		)
		(pad "2" smd circle
			(at 0.40005 0)
			(size 0 0)
			(layers "F.Cu" "F.Mask" "F.Paste")
			(net "PEX3_PCA9555_1_INT_N")
		)
	)
	(footprint ""
		(layer "F.Cu")
		(at 19.498564 -66.32194 -90)
		(property "Reference" "PC642"
			(at 0 0 270)
			(layer "F.SilkS")
			(hide yes)
			(effects
				(font
					(size 1.27 1.27)
				)
			)
		)
		(property "Value" ""
			(at 0 0 270)
			(layer "F.Fab")
			(effects
				(font
					(size 1.27 1.27)
				)
			)
		)
		(duplicate_pad_numbers_are_jumpers no)
		(fp_line
			(start -0.7874 0.4064)
			(end -0.7874 -0.4064)
			(stroke
				(width 0.1524)
				(type default)
			)
			(layer "F.SilkS")
		)
		(fp_line
			(start 0.7874 0.4064)
			(end -0.7874 0.4064)
			(stroke
				(width 0.1524)
				(type default)
			)
			(layer "F.SilkS")
		)
		(fp_line
			(start -0.7874 -0.4064)
			(end 0.7874 -0.4064)
			(stroke
				(width 0.1524)
				(type default)
			)
			(layer "F.SilkS")
		)
		(fp_line
			(start 0.7874 -0.4064)
			(end 0.7874 0.4064)
			(stroke
				(width 0.1524)
				(type default)
			)
			(layer "F.SilkS")
		)
		(fp_line
			(start -0.67945 0.3048)
			(end -0.67945 -0.305054)
			(stroke
				(width 0.1)
				(type default)
			)
			(layer "F.Fab")
		)
		(fp_line
			(start -0.12065 0.3048)
			(end -0.67945 0.3048)
			(stroke
				(width 0.1)
				(type default)
			)
			(layer "F.Fab")
		)
		(fp_line
			(start 0.120396 0.3048)
			(end 0.120396 0.2794)
			(stroke
				(width 0.1)
				(type default)
			)
			(layer "F.Fab")
		)
		(fp_line
			(start 0.67945 0.3048)
			(end 0.120396 0.3048)
			(stroke
				(width 0.1)
				(type default)
			)
			(layer "F.Fab")
		)
		(fp_line
			(start -0.12065 0.2794)
			(end -0.12065 0.3048)
			(stroke
				(width 0.1)
				(type default)
			)
			(layer "F.Fab")
		)
		(fp_line
			(start 0.120396 0.2794)
			(end -0.12065 0.2794)
			(stroke
				(width 0.1)
				(type default)
			)
			(layer "F.Fab")
		)
		(fp_line
			(start -0.12065 -0.2794)
			(end 0.12065 -0.2794)
			(stroke
				(width 0.1)
				(type default)
			)
			(layer "F.Fab")
		)
		(fp_line
			(start 0.12065 -0.2794)
			(end 0.12065 -0.3048)
			(stroke
				(width 0.1)
				(type default)
			)
			(layer "F.Fab")
		)
		(fp_line
			(start 0.12065 -0.3048)
			(end 0.67945 -0.3048)
			(stroke
				(width 0.1)
				(type default)
			)
			(layer "F.Fab")
		)
		(fp_line
			(start 0.67945 -0.3048)
			(end 0.67945 0.3048)
			(stroke
				(width 0.1)
				(type default)
			)
			(layer "F.Fab")
		)
		(fp_line
			(start -0.67945 -0.305054)
			(end -0.12065 -0.305054)
			(stroke
				(width 0.1)
				(type default)
			)
			(layer "F.Fab")
		)
		(fp_line
			(start -0.12065 -0.305054)
			(end -0.12065 -0.2794)
			(stroke
				(width 0.1)
				(type default)
			)
			(layer "F.Fab")
		)
		(pad "1" smd circle
			(at -0.40005 0 270)
			(size 0 0)
			(layers "F.Cu" "F.Mask" "F.Paste")
			(net "P12V_SSD0_CO_GATE")
		)
		(pad "2" smd circle
			(at 0.40005 0 270)
			(size 0 0)
			(layers "F.Cu" "F.Mask" "F.Paste")
			(net "GND")
		)
	)
)
